(kicad_pcb
	(version 20260206)
	(generator "pcbnew")
	(generator_version "10.0")
	(general
		(thickness 1.6)
		(legacy_teardrops no)
	)
	(paper "A4")
	(title_block
		(title "Bryce Canyon_F.DPB_16315-1-OCP.brd")
		(comment 1 "Bryce Canyon / footprints 346-353 of 2223")
	)
	(layers
		(0 "F.Cu" signal "TOP")
		(4 "In1.Cu" signal "L2GND")
		(6 "In2.Cu" signal "L3")
		(8 "In3.Cu" signal "L4GND")
		(10 "In4.Cu" signal "L5")
		(12 "In5.Cu" signal "L6VCC")
		(14 "In6.Cu" signal "L7VCC")
		(16 "In7.Cu" signal "L8")
		(18 "In8.Cu" signal "L9GND")
		(20 "In9.Cu" signal "L10")
		(22 "In10.Cu" signal "L11GND")
		(2 "B.Cu" signal "BOTTOM")
		(9 "F.Adhes" user "F.Adhesive")
		(11 "B.Adhes" user "B.Adhesive")
		(13 "F.Paste" user "Package Geometry/Pastemask Top")
		(15 "B.Paste" user "Package Geometry/Pastemask Bottom")
		(5 "F.SilkS" user "Ref Des/Silkscreen Top")
		(7 "B.SilkS" user "Ref Des/Silkscreen Bottom")
		(1 "F.Mask" user "Board Geometry/Soldermask Top")
		(3 "B.Mask" user "Board Geometry/Soldermask Bottom")
		(17 "Dwgs.User" user "User.Drawings")
		(19 "Cmts.User" user "User.Comments")
		(21 "Eco1.User" user "User.Eco1")
		(23 "Eco2.User" user "User.Eco2")
		(25 "Edge.Cuts" user "Board Geometry/Outline")
		(27 "Margin" user)
		(31 "F.CrtYd" user "Package Geometry/Place Bound Top")
		(29 "B.CrtYd" user "Package Geometry/Place Bound Bottom")
		(35 "F.Fab" user "Ref Des/Assembly Top")
		(33 "B.Fab" user "Ref Des/Assembly Bottom")
	)
	(footprint ""
		(layer "F.Cu")
		(at 176.657 -294.683942 90)
		(property "Reference" "R248"
			(at 0 0 90)
			(layer "F.SilkS")
			(hide yes)
			(effects
				(font
					(size 1.27 1.27)
				)
			)
		)
		(property "Value" "2R6F-GP"
			(at -0.0508 -4.8514 90)
			(unlocked yes)
			(layer "F.Fab")
			(hide yes)
			(effects
				(font
					(size 1.016 1.016)
					(thickness 0.1524)
				)
			)
		)
		(property "Device Type" "R1206H26"
			(at 0 -6.3754 90)
			(unlocked yes)
			(layer "F.Fab")
			(hide yes)
			(effects
				(font
					(size 1.016 1.016)
					(thickness 0.1524)
				)
			)
		)
		(duplicate_pad_numbers_are_jumpers no)
		(fp_line
			(start 1.016 -2.2352)
			(end 1.016 2.2352)
			(stroke
				(width 0.1524)
				(type default)
			)
			(layer "F.SilkS")
		)
		(fp_line
			(start -1.016 -2.2352)
			(end 1.016 -2.2352)
			(stroke
				(width 0.1524)
				(type default)
			)
			(layer "F.SilkS")
		)
		(fp_line
			(start 1.016 2.2352)
			(end -1.016 2.2352)
			(stroke
				(width 0.1524)
				(type default)
			)
			(layer "F.SilkS")
		)
		(fp_line
			(start -1.016 2.2352)
			(end -1.016 -2.2352)
			(stroke
				(width 0.1524)
				(type default)
			)
			(layer "F.SilkS")
		)
		(fp_rect
			(start -1.0922 2.3114)
			(end 1.0922 -2.3114)
			(stroke
				(width 0)
				(type default)
			)
			(fill no)
			(layer "F.CrtYd")
		)
		(fp_poly
			(pts
				(xy -1.0922 -2.3114) (xy 1.0922 -2.3114) (xy 1.0922 2.3114) (xy -1.0922 2.3114)
			)
			(stroke
				(width 0)
				(type default)
			)
			(fill no)
			(layer "F.Fab")
		)
		(pad "1" smd rect
			(at 0 -1.397 90)
			(size 1.651 1.27)
			(layers "F.Cu" "F.Mask" "F.Paste")
			(net "P12V_HDD5")
		)
		(pad "2" smd rect
			(at 0 1.397 90)
			(size 1.651 1.27)
			(layers "F.Cu" "F.Mask" "F.Paste")
			(net "12V_PRE_5")
		)
	)
	(footprint ""
		(layer "F.Cu")
		(at 44.1198 -141.1986 90)
		(property "Reference" "C614"
			(at 0 0 90)
			(layer "F.SilkS")
			(hide yes)
			(effects
				(font
					(size 1.27 1.27)
				)
			)
		)
		(property "Value" "SC10U16V5KX-7-GP-U"
			(at -0.0762 -6.1214 90)
			(unlocked yes)
			(layer "F.Fab")
			(hide yes)
			(effects
				(font
					(size 1.016 1.016)
					(thickness 0.1524)
				)
			)
		)
		(property "Device Type" "C805H58"
			(at -0.0762 -8.1534 90)
			(unlocked yes)
			(layer "F.Fab")
			(hide yes)
			(effects
				(font
					(size 1.016 1.016)
					(thickness 0.1524)
				)
			)
		)
		(duplicate_pad_numbers_are_jumpers no)
		(fp_line
			(start 0.635 0)
			(end -0.635 0)
			(stroke
				(width 0.508)
				(type default)
			)
			(layer "F.SilkS")
		)
		(fp_rect
			(start -0.9652 1.778)
			(end 0.9652 -1.778)
			(stroke
				(width 0)
				(type default)
			)
			(fill no)
			(layer "F.CrtYd")
		)
		(fp_poly
			(pts
				(xy -0.9652 -1.778) (xy 0.9652 -1.778) (xy 0.9652 1.778) (xy -0.9652 1.778)
			)
			(stroke
				(width 0)
				(type default)
			)
			(fill no)
			(layer "F.Fab")
		)
		(pad "1" smd rect
			(at 0 -0.9652 90)
			(size 1.397 1.143)
			(layers "F.Cu" "F.Mask" "F.Paste")
			(net "P12V_A_VIN_U21")
		)
		(pad "2" smd rect
			(at 0 0.9652 90)
			(size 1.397 1.143)
			(layers "F.Cu" "F.Mask" "F.Paste")
			(net "GND")
		)
	)
	(footprint ""
		(layer "F.Cu")
		(at 141.042898 -169.523918 90)
		(property "Reference" "C257"
			(at 0 0 90)
			(layer "F.SilkS")
			(hide yes)
			(effects
				(font
					(size 1.27 1.27)
				)
			)
		)
		(property "Value" "SCD033U25V2KX-GP"
			(at 1.1811 -2.7051 90)
			(unlocked yes)
			(layer "F.Fab")
			(hide yes)
			(effects
				(font
					(size 1.016 1.016)
					(thickness 0.1524)
				)
			)
		)
		(property "Device Type" "C402H22"
			(at 1.1811 -4.2291 90)
			(unlocked yes)
			(layer "F.Fab")
			(hide yes)
			(effects
				(font
					(size 1.016 1.016)
					(thickness 0.1524)
				)
			)
		)
		(duplicate_pad_numbers_are_jumpers no)
		(fp_rect
			(start -0.4318 0.9525)
			(end 0.4318 -0.9525)
			(stroke
				(width 0)
				(type default)
			)
			(fill no)
			(layer "F.CrtYd")
		)
		(fp_rect
			(start -0.4318 0.9525)
			(end 0.4318 -0.9525)
			(stroke
				(width 0)
				(type default)
			)
			(fill no)
			(layer "F.Fab")
		)
		(pad "1" smd custom
			(at 0 -0.4445 90)
			(size 0.1524 0.1524)
			(layers "F.Cu" "F.Mask" "F.Paste")
			(net "P12V_A")
			(options
				(clearance outline)
				(anchor circle)
			)
			(primitives
				(gr_poly
					(pts
						(arc
							(start 0.3048 -0.2032)
							(mid 0.275042 -0.275042)
							(end 0.2032 -0.3048)
						)
						(arc
							(start -0.2032 -0.3048)
							(mid -0.275042 -0.275042)
							(end -0.3048 -0.2032)
						)
						(arc
							(start -0.3048 0.2032)
							(mid -0.275042 0.275042)
							(end -0.2032 0.3048)
						)
						(arc
							(start 0.2032 0.3048)
							(mid 0.275042 0.275042)
							(end 0.3048 0.2032)
						)
					)
					(width 0)
					(fill yes)
				)
			)
		)
		(pad "2" smd custom
			(at 0 0.4445 90)
			(size 0.1524 0.1524)
			(layers "F.Cu" "F.Mask" "F.Paste")
			(net "SW_HDD_N16")
			(options
				(clearance outline)
				(anchor circle)
			)
			(primitives
				(gr_poly
					(pts
						(arc
							(start 0.3048 -0.2032)
							(mid 0.275042 -0.275042)
							(end 0.2032 -0.3048)
						)
						(arc
							(start -0.2032 -0.3048)
							(mid -0.275042 -0.275042)
							(end -0.3048 -0.2032)
						)
						(arc
							(start -0.3048 0.2032)
							(mid -0.275042 0.275042)
							(end -0.2032 0.3048)
						)
						(arc
							(start 0.2032 0.3048)
							(mid 0.275042 0.275042)
							(end 0.3048 0.2032)
						)
					)
					(width 0)
					(fill yes)
				)
			)
		)
	)
	(footprint ""
		(layer "F.Cu")
		(at 164.279326 -303.88306)
		(property "Reference" "Q256"
			(at 0 0 0)
			(layer "F.SilkS")
			(hide yes)
			(effects
				(font
					(size 1.27 1.27)
				)
			)
		)
		(property "Value" "2N7002K-2-GP"
			(at 0.127 -8.9662 0)
			(unlocked yes)
			(layer "F.Fab")
			(hide yes)
			(effects
				(font
					(size 1.016 1.016)
					(thickness 0.1524)
				)
			)
		)
		(property "Device Type" "SOT23DGS2D4H44"
			(at 0.127 -10.4902 0)
			(unlocked yes)
			(layer "F.Fab")
			(hide yes)
			(effects
				(font
					(size 1.016 1.016)
					(thickness 0.1524)
				)
			)
		)
		(duplicate_pad_numbers_are_jumpers no)
		(fp_line
			(start -1.651 -1.778)
			(end -1.651 1.778)
			(stroke
				(width 0.1524)
				(type default)
			)
			(layer "F.SilkS")
		)
		(fp_line
			(start -1.651 1.778)
			(end 1.651 1.778)
			(stroke
				(width 0.1524)
				(type default)
			)
			(layer "F.SilkS")
		)
		(fp_line
			(start 1.651 -1.778)
			(end -1.651 -1.778)
			(stroke
				(width 0.1524)
				(type default)
			)
			(layer "F.SilkS")
		)
		(fp_line
			(start 1.651 1.778)
			(end 1.651 -1.778)
			(stroke
				(width 0.1524)
				(type default)
			)
			(layer "F.SilkS")
		)
		(fp_poly
			(pts
				(xy -1.778 1.8796) (xy -1.778 -1.8796) (xy 1.778 -1.8796) (xy 1.778 1.8796)
			)
			(stroke
				(width 0)
				(type default)
			)
			(fill no)
			(layer "F.CrtYd")
		)
		(fp_poly
			(pts
				(xy -1.778 1.8796) (xy -1.778 -1.8796) (xy 1.778 -1.8796) (xy 1.778 1.8796)
			)
			(stroke
				(width 0)
				(type default)
			)
			(fill no)
			(layer "F.Fab")
		)
		(pad "D" smd custom
			(at 0 -0.9525)
			(size 0.1905 0.1905)
			(layers "F.Cu" "F.Mask" "F.Paste")
			(net "FLT_HDD29_N")
			(options
				(clearance outline)
				(anchor circle)
			)
			(primitives
				(gr_poly
					(pts
						(arc
							(start -0.1778 0.5715)
							(mid -0.321484 0.511984)
							(end -0.381 0.3683)
						)
						(arc
							(start -0.381 -0.3683)
							(mid -0.321484 -0.511984)
							(end -0.1778 -0.5715)
						)
						(arc
							(start 0.1778 -0.5715)
							(mid 0.321484 -0.511984)
							(end 0.381 -0.3683)
						)
						(arc
							(start 0.381 0.3683)
							(mid 0.321484 0.511984)
							(end 0.1778 0.5715)
						)
					)
					(width 0)
					(fill yes)
				)
			)
		)
		(pad "G" smd custom
			(at -0.98425 0.9525)
			(size 0.1905 0.1905)
			(layers "F.Cu" "F.Mask" "F.Paste")
			(net "DRIVE_B_29_FLT_LED")
			(options
				(clearance outline)
				(anchor circle)
			)
			(primitives
				(gr_poly
					(pts
						(arc
							(start -0.1778 0.5715)
							(mid -0.321484 0.511984)
							(end -0.381 0.3683)
						)
						(arc
							(start -0.381 -0.3683)
							(mid -0.321484 -0.511984)
							(end -0.1778 -0.5715)
						)
						(arc
							(start 0.1778 -0.5715)
							(mid 0.321484 -0.511984)
							(end 0.381 -0.3683)
						)
						(arc
							(start 0.381 0.3683)
							(mid 0.321484 0.511984)
							(end 0.1778 0.5715)
						)
					)
					(width 0)
					(fill yes)
				)
			)
		)
		(pad "S" smd custom
			(at 0.98425 0.9525)
			(size 0.1905 0.1905)
			(layers "F.Cu" "F.Mask" "F.Paste")
			(net "GND")
			(options
				(clearance outline)
				(anchor circle)
			)
			(primitives
				(gr_poly
					(pts
						(arc
							(start -0.1778 0.5715)
							(mid -0.321484 0.511984)
							(end -0.381 0.3683)
						)
						(arc
							(start -0.381 -0.3683)
							(mid -0.321484 -0.511984)
							(end -0.1778 -0.5715)
						)
						(arc
							(start 0.1778 -0.5715)
							(mid 0.321484 -0.511984)
							(end 0.381 -0.3683)
						)
						(arc
							(start 0.381 0.3683)
							(mid 0.321484 0.511984)
							(end 0.1778 0.5715)
						)
					)
					(width 0)
					(fill yes)
				)
			)
		)
	)
	(footprint ""
		(layer "F.Cu")
		(at 79.974948 -276.649942 180)
		(property "Reference" "D2"
			(at 0 0 180)
			(layer "F.SilkS")
			(hide yes)
			(effects
				(font
					(size 1.27 1.27)
				)
			)
		)
		(property "Value" "RB551V30-GP"
			(at 0 -6.7818 180)
			(unlocked yes)
			(layer "F.Fab")
			(hide yes)
			(effects
				(font
					(size 1.016 1.016)
					(thickness 0.1524)
				)
			)
		)
		(property "Device Type" "SOD323AKH38"
			(at 0 -8.6868 180)
			(unlocked yes)
			(layer "F.Fab")
			(hide yes)
			(effects
				(font
					(size 1.016 1.016)
					(thickness 0.1524)
				)
			)
		)
		(duplicate_pad_numbers_are_jumpers no)
		(fp_line
			(start 0.889 2.159)
			(end -0.889 2.159)
			(stroke
				(width 0.1524)
				(type default)
			)
			(layer "F.SilkS")
		)
		(fp_line
			(start 0.889 -1.9304)
			(end 0.889 2.159)
			(stroke
				(width 0.1524)
				(type default)
			)
			(layer "F.SilkS")
		)
		(fp_line
			(start 0.762 2.0574)
			(end -0.762 2.0574)
			(stroke
				(width 0.508)
				(type default)
			)
			(layer "F.SilkS")
		)
		(fp_line
			(start -0.889 2.159)
			(end -0.889 -1.9304)
			(stroke
				(width 0.1524)
				(type default)
			)
			(layer "F.SilkS")
		)
		(fp_line
			(start -0.889 -1.9304)
			(end 0.889 -1.9304)
			(stroke
				(width 0.1524)
				(type default)
			)
			(layer "F.SilkS")
		)
		(fp_rect
			(start -1.016 2.3114)
			(end 1.016 -2.0066)
			(stroke
				(width 0)
				(type default)
			)
			(fill no)
			(layer "F.CrtYd")
		)
		(fp_poly
			(pts
				(xy -1.016 -2.0066) (xy 1.016 -2.0066) (xy 1.016 2.3114) (xy -1.016 2.3114)
			)
			(stroke
				(width 0)
				(type default)
			)
			(fill no)
			(layer "F.Fab")
		)
		(pad "A" smd rect
			(at 0 -1.143 180)
			(size 0.5588 1.016)
			(layers "F.Cu" "F.Mask" "F.Paste")
			(net "SW_HDD_R2")
		)
		(pad "K" smd rect
			(at 0 1.143 180)
			(size 0.5588 1.016)
			(layers "F.Cu" "F.Mask" "F.Paste")
			(net "SW_HDD_N2")
		)
	)
	(footprint ""
		(layer "F.Cu")
		(at 205.232254 -14.313916)
		(property "Reference" "TC17"
			(at 0 0 0)
			(layer "F.SilkS")
			(hide yes)
			(effects
				(font
					(size 1.27 1.27)
				)
			)
		)
		(property "Value" "SE270U16VM-8-GP"
			(at -4.5974 -2.54 0)
			(unlocked yes)
			(layer "F.Fab")
			(hide yes)
			(effects
				(font
					(size 1.016 1.016)
					(thickness 0.1524)
				)
			)
		)
		(property "Device Type" "SE361416H394"
			(at -4.5974 -4.064 0)
			(unlocked yes)
			(layer "F.Fab")
			(hide yes)
			(effects
				(font
					(size 1.016 1.016)
					(thickness 0.1524)
				)
			)
		)
		(duplicate_pad_numbers_are_jumpers no)
		(fp_line
			(start -3.556 -3.4163)
			(end -2.3622 -4.6101)
			(stroke
				(width 0.1524)
				(type default)
			)
			(layer "F.SilkS")
		)
		(fp_line
			(start -3.556 4.6101)
			(end -3.556 -3.4163)
			(stroke
				(width 0.1524)
				(type default)
			)
			(layer "F.SilkS")
		)
		(fp_line
			(start -2.3622 -4.6101)
			(end 2.3622 -4.6101)
			(stroke
				(width 0.1524)
				(type default)
			)
			(layer "F.SilkS")
		)
		(fp_line
			(start 2.3622 -4.6101)
			(end 3.556 -3.4163)
			(stroke
				(width 0.1524)
				(type default)
			)
			(layer "F.SilkS")
		)
		(fp_line
			(start 3.556 -3.4163)
			(end 3.556 4.6101)
			(stroke
				(width 0.1524)
				(type default)
			)
			(layer "F.SilkS")
		)
		(fp_line
			(start 3.556 4.6101)
			(end -3.556 4.6101)
			(stroke
				(width 0.1524)
				(type default)
			)
			(layer "F.SilkS")
		)
		(fp_rect
			(start -3.302 3.6449)
			(end 3.302 -3.6449)
			(stroke
				(width 0)
				(type default)
			)
			(fill no)
			(layer "F.CrtYd")
		)
		(fp_poly
			(pts
				(xy 3.81 4.6863) (xy 3.81 -3.4925) (xy 3.302 -3.4925) (xy 3.302 3.6449) (xy -3.302 3.6449) (xy -3.302 -3.6449)
				(xy 3.302 -3.6449) (xy 3.302 -3.5052) (xy 3.81 -3.5052) (xy 3.81 -4.6863) (xy -3.81 -4.6863) (xy -3.81 4.6863)
			)
			(stroke
				(width 0)
				(type default)
			)
			(fill no)
			(layer "F.CrtYd")
		)
		(fp_rect
			(start -3.81 4.6863)
			(end 3.81 -4.6863)
			(stroke
				(width 0)
				(type default)
			)
			(fill no)
			(layer "F.Fab")
		)
		(pad "1" smd rect
			(at 0 -2.574036)
			(size 1.4224 3.556)
			(layers "F.Cu" "F.Mask" "F.Paste")
			(net "P12V_A")
		)
		(pad "2" smd rect
			(at 0 2.574036)
			(size 1.4224 3.556)
			(layers "F.Cu" "F.Mask" "F.Paste")
			(net "GND")
		)
	)
	(footprint ""
		(layer "F.Cu")
		(at 48.297846 -282.060142 -90)
		(property "Reference" "C61"
			(at 0 0 270)
			(layer "F.SilkS")
			(hide yes)
			(effects
				(font
					(size 1.27 1.27)
				)
			)
		)
		(property "Value" "SCD033U25V2KX-GP"
			(at 1.1811 -2.7051 270)
			(unlocked yes)
			(layer "F.Fab")
			(hide yes)
			(effects
				(font
					(size 1.016 1.016)
					(thickness 0.1524)
				)
			)
		)
		(property "Device Type" "C402H22"
			(at 1.1811 -4.2291 270)
			(unlocked yes)
			(layer "F.Fab")
			(hide yes)
			(effects
				(font
					(size 1.016 1.016)
					(thickness 0.1524)
				)
			)
		)
		(duplicate_pad_numbers_are_jumpers no)
		(fp_rect
			(start -0.4318 0.9525)
			(end 0.4318 -0.9525)
			(stroke
				(width 0)
				(type default)
			)
			(fill no)
			(layer "F.CrtYd")
		)
		(fp_rect
			(start -0.4318 0.9525)
			(end 0.4318 -0.9525)
			(stroke
				(width 0)
				(type default)
			)
			(fill no)
			(layer "F.Fab")
		)
		(pad "1" smd custom
			(at 0 -0.4445 270)
			(size 0.1524 0.1524)
			(layers "F.Cu" "F.Mask" "F.Paste")
			(net "SW_HDD_P1")
			(options
				(clearance outline)
				(anchor circle)
			)
			(primitives
				(gr_poly
					(pts
						(arc
							(start 0.3048 -0.2032)
							(mid 0.275042 -0.275042)
							(end 0.2032 -0.3048)
						)
						(arc
							(start -0.2032 -0.3048)
							(mid -0.275042 -0.275042)
							(end -0.3048 -0.2032)
						)
						(arc
							(start -0.3048 0.2032)
							(mid -0.275042 0.275042)
							(end -0.2032 0.3048)
						)
						(arc
							(start 0.2032 0.3048)
							(mid 0.275042 0.275042)
							(end 0.3048 0.2032)
						)
					)
					(width 0)
					(fill yes)
				)
			)
		)
		(pad "2" smd custom
			(at 0 0.4445 270)
			(size 0.1524 0.1524)
			(layers "F.Cu" "F.Mask" "F.Paste")
			(net "GND")
			(options
				(clearance outline)
				(anchor circle)
			)
			(primitives
				(gr_poly
					(pts
						(arc
							(start 0.3048 -0.2032)
							(mid 0.275042 -0.275042)
							(end 0.2032 -0.3048)
						)
						(arc
							(start -0.2032 -0.3048)
							(mid -0.275042 -0.275042)
							(end -0.3048 -0.2032)
						)
						(arc
							(start -0.3048 0.2032)
							(mid -0.275042 0.275042)
							(end -0.2032 0.3048)
						)
						(arc
							(start 0.2032 0.3048)
							(mid 0.275042 0.275042)
							(end 0.3048 0.2032)
						)
					)
					(width 0)
					(fill yes)
				)
			)
		)
	)
	(footprint ""
		(layer "F.Cu")
		(at 405.9936 -282.702 180)
		(property "Reference" "C153"
			(at 0 0 180)
			(layer "F.SilkS")
			(hide yes)
			(effects
				(font
					(size 1.27 1.27)
				)
			)
		)
		(property "Value" "SCD033U25V2KX-GP"
			(at 1.1811 -2.7051 180)
			(unlocked yes)
			(layer "F.Fab")
			(hide yes)
			(effects
				(font
					(size 1.016 1.016)
					(thickness 0.1524)
				)
			)
		)
		(property "Device Type" "C402H22"
			(at 1.1811 -4.2291 180)
			(unlocked yes)
			(layer "F.Fab")
			(hide yes)
			(effects
				(font
					(size 1.016 1.016)
					(thickness 0.1524)
				)
			)
		)
		(duplicate_pad_numbers_are_jumpers no)
		(fp_rect
			(start -0.4318 0.9525)
			(end 0.4318 -0.9525)
			(stroke
				(width 0)
				(type default)
			)
			(fill no)
			(layer "F.CrtYd")
		)
		(fp_rect
			(start -0.4318 0.9525)
			(end 0.4318 -0.9525)
			(stroke
				(width 0)
				(type default)
			)
			(fill no)
			(layer "F.Fab")
		)
		(pad "1" smd custom
			(at 0 -0.4445 180)
			(size 0.1524 0.1524)
			(layers "F.Cu" "F.Mask" "F.Paste")
			(net "P12V_A")
			(options
				(clearance outline)
				(anchor circle)
			)
			(primitives
				(gr_poly
					(pts
						(arc
							(start 0.3048 -0.2032)
							(mid 0.275042 -0.275042)
							(end 0.2032 -0.3048)
						)
						(arc
							(start -0.2032 -0.3048)
							(mid -0.275042 -0.275042)
							(end -0.3048 -0.2032)
						)
						(arc
							(start -0.3048 0.2032)
							(mid -0.275042 0.275042)
							(end -0.2032 0.3048)
						)
						(arc
							(start 0.2032 0.3048)
							(mid 0.275042 0.275042)
							(end 0.3048 0.2032)
						)
					)
					(width 0)
					(fill yes)
				)
			)
		)
		(pad "2" smd custom
			(at 0 0.4445 180)
			(size 0.1524 0.1524)
			(layers "F.Cu" "F.Mask" "F.Paste")
			(net "SW_HDD_N8")
			(options
				(clearance outline)
				(anchor circle)
			)
			(primitives
				(gr_poly
					(pts
						(arc
							(start 0.3048 -0.2032)
							(mid 0.275042 -0.275042)
							(end 0.2032 -0.3048)
						)
						(arc
							(start -0.2032 -0.3048)
							(mid -0.275042 -0.275042)
							(end -0.3048 -0.2032)
						)
						(arc
							(start -0.3048 0.2032)
							(mid -0.275042 0.275042)
							(end -0.2032 0.3048)
						)
						(arc
							(start 0.2032 0.3048)
							(mid 0.275042 0.275042)
							(end 0.3048 0.2032)
						)
					)
					(width 0)
					(fill yes)
				)
			)
		)
	)
)
